(kicad_pcb
	(version 20260206)
	(generator "pcbnew")
	(generator_version "10.0")
	(general
		(thickness 1.6)
		(legacy_teardrops no)
	)
	(paper "A4")
	(title_block
		(title "03242023_DA0F0TMBIJ0_F0T_Motherboard_J_brd_V01_OCP.brd")
		(comment 1 "Grand Teton / footprints 4662-4668 of 6105")
	)
	(layers
		(0 "F.Cu" signal "TOP")
		(4 "In1.Cu" signal "GND")
		(6 "In2.Cu" signal "IN1")
		(8 "In3.Cu" signal "GND1")
		(10 "In4.Cu" signal "IN2")
		(12 "In5.Cu" signal "GND2")
		(14 "In6.Cu" signal "IN3")
		(16 "In7.Cu" signal "GND3")
		(18 "In8.Cu" signal "VCC")
		(20 "In9.Cu" signal "VCC1")
		(22 "In10.Cu" signal "GND4")
		(24 "In11.Cu" signal "IN4")
		(26 "In12.Cu" signal "GND5")
		(28 "In13.Cu" signal "IN5")
		(30 "In14.Cu" signal "GND6")
		(32 "In15.Cu" signal "IN6")
		(34 "In16.Cu" signal "GND7")
		(2 "B.Cu" signal "BOTTOM")
		(9 "F.Adhes" user "F.Adhesive")
		(11 "B.Adhes" user "B.Adhesive")
		(13 "F.Paste" user "Package Geometry/Pastemask Top")
		(15 "B.Paste" user "Package Geometry/Pastemask Bottom")
		(5 "F.SilkS" user "Ref Des/Silkscreen Top")
		(7 "B.SilkS" user "Ref Des/Silkscreen Bottom")
		(1 "F.Mask" user "Board Geometry/Soldermask Top")
		(3 "B.Mask" user "Board Geometry/Soldermask Bottom")
		(17 "Dwgs.User" user "User.Drawings")
		(19 "Cmts.User" user "User.Comments")
		(21 "Eco1.User" user "User.Eco1")
		(23 "Eco2.User" user "User.Eco2")
		(25 "Edge.Cuts" user "Board Geometry/Outline")
		(27 "Margin" user)
		(31 "F.CrtYd" user "Package Geometry/Place Bound Top")
		(29 "B.CrtYd" user "Package Geometry/Place Bound Bottom")
		(35 "F.Fab" user "Ref Des/Assembly Top")
		(33 "B.Fab" user "Ref Des/Assembly Bottom")
	)
	(footprint ""
		(layer "B.Cu")
		(at 407.91257 -165.504368 180)
		(property "Reference" "PC642"
			(at 0 0 0)
			(layer "B.SilkS")
			(hide yes)
			(effects
				(font
					(size 1.27 1.27)
				)
				(justify mirror)
			)
		)
		(property "Value" ""
			(at 0 0 0)
			(layer "B.Fab")
			(effects
				(font
					(size 1.27 1.27)
				)
				(justify mirror)
			)
		)
		(duplicate_pad_numbers_are_jumpers no)
		(fp_line
			(start 1.524 0.762)
			(end 1.524 -0.762)
			(stroke
				(width 0.1524)
				(type default)
			)
			(layer "B.SilkS")
		)
		(fp_line
			(start 1.524 -0.762)
			(end -1.524 -0.762)
			(stroke
				(width 0.1524)
				(type default)
			)
			(layer "B.SilkS")
		)
		(fp_line
			(start -1.524 0.762)
			(end 1.524 0.762)
			(stroke
				(width 0.1524)
				(type default)
			)
			(layer "B.SilkS")
		)
		(fp_line
			(start -1.524 -0.762)
			(end -1.524 0.762)
			(stroke
				(width 0.1524)
				(type default)
			)
			(layer "B.SilkS")
		)
		(fp_line
			(start 1.1049 0.724916)
			(end -1.1049 0.724916)
			(stroke
				(width 0.1)
				(type default)
			)
			(layer "B.Fab")
		)
		(fp_line
			(start 1.1049 -0.724916)
			(end 1.1049 0.724916)
			(stroke
				(width 0.1)
				(type default)
			)
			(layer "B.Fab")
		)
		(fp_line
			(start -1.1049 0.724916)
			(end -1.1049 -0.724916)
			(stroke
				(width 0.1)
				(type default)
			)
			(layer "B.Fab")
		)
		(fp_line
			(start -1.1049 -0.724916)
			(end 1.1049 -0.724916)
			(stroke
				(width 0.1)
				(type default)
			)
			(layer "B.Fab")
		)
		(pad "1" smd rect
			(at 0.889 0 180)
			(size 1.016 1.27)
			(layers "B.Cu" "B.Mask" "B.Paste")
			(net "PVCCD_HV_CPU0")
		)
		(pad "2" smd rect
			(at -0.889 0 180)
			(size 1.016 1.27)
			(layers "B.Cu" "B.Mask" "B.Paste")
			(net "GND")
		)
	)
	(footprint ""
		(layer "B.Cu")
		(at 130.860546 -341.218012 -90)
		(property "Reference" "PC514_P1_5"
			(at 0 0 90)
			(layer "B.SilkS")
			(hide yes)
			(effects
				(font
					(size 1.27 1.27)
				)
				(justify mirror)
			)
		)
		(property "Value" ""
			(at 0 0 90)
			(layer "B.Fab")
			(effects
				(font
					(size 1.27 1.27)
				)
				(justify mirror)
			)
		)
		(duplicate_pad_numbers_are_jumpers no)
		(fp_line
			(start -1.524 0.762)
			(end 1.524 0.762)
			(stroke
				(width 0.1524)
				(type default)
			)
			(layer "B.SilkS")
		)
		(fp_line
			(start 1.524 0.762)
			(end 1.524 -0.762)
			(stroke
				(width 0.1524)
				(type default)
			)
			(layer "B.SilkS")
		)
		(fp_line
			(start -1.524 -0.762)
			(end -1.524 0.762)
			(stroke
				(width 0.1524)
				(type default)
			)
			(layer "B.SilkS")
		)
		(fp_line
			(start 1.524 -0.762)
			(end -1.524 -0.762)
			(stroke
				(width 0.1524)
				(type default)
			)
			(layer "B.SilkS")
		)
		(fp_line
			(start -1.1049 0.724916)
			(end -1.1049 -0.724916)
			(stroke
				(width 0.1)
				(type default)
			)
			(layer "B.Fab")
		)
		(fp_line
			(start 1.1049 0.724916)
			(end -1.1049 0.724916)
			(stroke
				(width 0.1)
				(type default)
			)
			(layer "B.Fab")
		)
		(fp_line
			(start -1.1049 -0.724916)
			(end 1.1049 -0.724916)
			(stroke
				(width 0.1)
				(type default)
			)
			(layer "B.Fab")
		)
		(fp_line
			(start 1.1049 -0.724916)
			(end 1.1049 0.724916)
			(stroke
				(width 0.1)
				(type default)
			)
			(layer "B.Fab")
		)
		(pad "1" smd rect
			(at 0.889 0 270)
			(size 1.016 1.27)
			(layers "B.Cu" "B.Mask" "B.Paste")
			(net "SW_P12V_PVCCIN_CPU1_FLT")
		)
		(pad "2" smd rect
			(at -0.889 0 270)
			(size 1.016 1.27)
			(layers "B.Cu" "B.Mask" "B.Paste")
			(net "GND")
		)
	)
	(footprint ""
		(layer "B.Cu")
		(at 42.686732 -353.567492 90)
		(property "Reference" "PC1202_P1_4"
			(at 0 0 90)
			(layer "B.SilkS")
			(hide yes)
			(effects
				(font
					(size 1.27 1.27)
				)
				(justify mirror)
			)
		)
		(property "Value" ""
			(at 0 0 90)
			(layer "B.Fab")
			(effects
				(font
					(size 1.27 1.27)
				)
				(justify mirror)
			)
		)
		(duplicate_pad_numbers_are_jumpers no)
		(fp_line
			(start 1.524 -0.762)
			(end -1.524 -0.762)
			(stroke
				(width 0.1524)
				(type default)
			)
			(layer "B.SilkS")
		)
		(fp_line
			(start -1.524 -0.762)
			(end -1.524 0.762)
			(stroke
				(width 0.1524)
				(type default)
			)
			(layer "B.SilkS")
		)
		(fp_line
			(start 1.524 0.762)
			(end 1.524 -0.762)
			(stroke
				(width 0.1524)
				(type default)
			)
			(layer "B.SilkS")
		)
		(fp_line
			(start -1.524 0.762)
			(end 1.524 0.762)
			(stroke
				(width 0.1524)
				(type default)
			)
			(layer "B.SilkS")
		)
		(fp_line
			(start 1.1049 -0.724916)
			(end 1.1049 0.724916)
			(stroke
				(width 0.1)
				(type default)
			)
			(layer "B.Fab")
		)
		(fp_line
			(start -1.1049 -0.724916)
			(end 1.1049 -0.724916)
			(stroke
				(width 0.1)
				(type default)
			)
			(layer "B.Fab")
		)
		(fp_line
			(start 1.1049 0.724916)
			(end -1.1049 0.724916)
			(stroke
				(width 0.1)
				(type default)
			)
			(layer "B.Fab")
		)
		(fp_line
			(start -1.1049 0.724916)
			(end -1.1049 -0.724916)
			(stroke
				(width 0.1)
				(type default)
			)
			(layer "B.Fab")
		)
		(pad "1" smd rect
			(at 0.889 0 90)
			(size 1.016 1.27)
			(layers "B.Cu" "B.Mask" "B.Paste")
			(net "SW_P12V_PVCCFA_EHV_FIVRA_CPU1_L")
		)
		(pad "2" smd rect
			(at -0.889 0 90)
			(size 1.016 1.27)
			(layers "B.Cu" "B.Mask" "B.Paste")
			(net "GND")
		)
	)
	(footprint ""
		(layer "B.Cu")
		(at 22.48916 -169.659808 180)
		(property "Reference" "R2575"
			(at 0 0 0)
			(layer "B.SilkS")
			(hide yes)
			(effects
				(font
					(size 1.27 1.27)
				)
				(justify mirror)
			)
		)
		(property "Value" ""
			(at 0 0 0)
			(layer "B.Fab")
			(effects
				(font
					(size 1.27 1.27)
				)
				(justify mirror)
			)
		)
		(duplicate_pad_numbers_are_jumpers no)
		(fp_line
			(start 0.7874 0.4064)
			(end 0.7874 -0.4064)
			(stroke
				(width 0.1524)
				(type default)
			)
			(layer "B.SilkS")
		)
		(fp_line
			(start 0.7874 -0.4064)
			(end -0.7874 -0.4064)
			(stroke
				(width 0.1524)
				(type default)
			)
			(layer "B.SilkS")
		)
		(fp_line
			(start -0.7874 0.4064)
			(end 0.7874 0.4064)
			(stroke
				(width 0.1524)
				(type default)
			)
			(layer "B.SilkS")
		)
		(fp_line
			(start -0.7874 -0.4064)
			(end -0.7874 0.4064)
			(stroke
				(width 0.1524)
				(type default)
			)
			(layer "B.SilkS")
		)
		(fp_line
			(start 0.67945 0.3048)
			(end 0.67945 -0.305054)
			(stroke
				(width 0.1)
				(type default)
			)
			(layer "B.Fab")
		)
		(fp_line
			(start 0.67945 -0.305054)
			(end 0.12065 -0.305054)
			(stroke
				(width 0.1)
				(type default)
			)
			(layer "B.Fab")
		)
		(fp_line
			(start 0.12065 0.3048)
			(end 0.67945 0.3048)
			(stroke
				(width 0.1)
				(type default)
			)
			(layer "B.Fab")
		)
		(fp_line
			(start 0.12065 0.2794)
			(end 0.12065 0.3048)
			(stroke
				(width 0.1)
				(type default)
			)
			(layer "B.Fab")
		)
		(fp_line
			(start 0.12065 -0.2794)
			(end -0.12065 -0.2794)
			(stroke
				(width 0.1)
				(type default)
			)
			(layer "B.Fab")
		)
		(fp_line
			(start 0.12065 -0.305054)
			(end 0.12065 -0.2794)
			(stroke
				(width 0.1)
				(type default)
			)
			(layer "B.Fab")
		)
		(fp_line
			(start -0.120396 0.3048)
			(end -0.120396 0.2794)
			(stroke
				(width 0.1)
				(type default)
			)
			(layer "B.Fab")
		)
		(fp_line
			(start -0.120396 0.2794)
			(end 0.12065 0.2794)
			(stroke
				(width 0.1)
				(type default)
			)
			(layer "B.Fab")
		)
		(fp_line
			(start -0.12065 -0.2794)
			(end -0.12065 -0.3048)
			(stroke
				(width 0.1)
				(type default)
			)
			(layer "B.Fab")
		)
		(fp_line
			(start -0.12065 -0.3048)
			(end -0.67945 -0.3048)
			(stroke
				(width 0.1)
				(type default)
			)
			(layer "B.Fab")
		)
		(fp_line
			(start -0.67945 0.3048)
			(end -0.120396 0.3048)
			(stroke
				(width 0.1)
				(type default)
			)
			(layer "B.Fab")
		)
		(fp_line
			(start -0.67945 -0.3048)
			(end -0.67945 0.3048)
			(stroke
				(width 0.1)
				(type default)
			)
			(layer "B.Fab")
		)
		(pad "1" smd circle
			(at 0.40005 0)
			(size 0 0)
			(layers "B.Cu" "B.Mask" "B.Paste")
			(net "P3V3_AUX")
		)
		(pad "2" smd circle
			(at -0.40005 0)
			(size 0 0)
			(layers "B.Cu" "B.Mask" "B.Paste")
			(net "PWRGD_PVCCD_HV_CPU1_R")
		)
	)
	(footprint ""
		(layer "B.Cu")
		(at 312.443622 -33.010348)
		(property "Reference" "R1298"
			(at 0 0 0)
			(layer "B.SilkS")
			(hide yes)
			(effects
				(font
					(size 1.27 1.27)
				)
				(justify mirror)
			)
		)
		(property "Value" ""
			(at 0 0 0)
			(layer "B.Fab")
			(effects
				(font
					(size 1.27 1.27)
				)
				(justify mirror)
			)
		)
		(duplicate_pad_numbers_are_jumpers no)
		(fp_line
			(start -0.7874 -0.4064)
			(end -0.7874 0.4064)
			(stroke
				(width 0.1524)
				(type default)
			)
			(layer "B.SilkS")
		)
		(fp_line
			(start -0.7874 0.4064)
			(end 0.7874 0.4064)
			(stroke
				(width 0.1524)
				(type default)
			)
			(layer "B.SilkS")
		)
		(fp_line
			(start 0.7874 -0.4064)
			(end -0.7874 -0.4064)
			(stroke
				(width 0.1524)
				(type default)
			)
			(layer "B.SilkS")
		)
		(fp_line
			(start 0.7874 0.4064)
			(end 0.7874 -0.4064)
			(stroke
				(width 0.1524)
				(type default)
			)
			(layer "B.SilkS")
		)
		(fp_line
			(start -0.67945 -0.3048)
			(end -0.67945 0.3048)
			(stroke
				(width 0.1)
				(type default)
			)
			(layer "B.Fab")
		)
		(fp_line
			(start -0.67945 0.3048)
			(end -0.120396 0.3048)
			(stroke
				(width 0.1)
				(type default)
			)
			(layer "B.Fab")
		)
		(fp_line
			(start -0.12065 -0.3048)
			(end -0.67945 -0.3048)
			(stroke
				(width 0.1)
				(type default)
			)
			(layer "B.Fab")
		)
		(fp_line
			(start -0.12065 -0.2794)
			(end -0.12065 -0.3048)
			(stroke
				(width 0.1)
				(type default)
			)
			(layer "B.Fab")
		)
		(fp_line
			(start -0.120396 0.2794)
			(end 0.12065 0.2794)
			(stroke
				(width 0.1)
				(type default)
			)
			(layer "B.Fab")
		)
		(fp_line
			(start -0.120396 0.3048)
			(end -0.120396 0.2794)
			(stroke
				(width 0.1)
				(type default)
			)
			(layer "B.Fab")
		)
		(fp_line
			(start 0.12065 -0.305054)
			(end 0.12065 -0.2794)
			(stroke
				(width 0.1)
				(type default)
			)
			(layer "B.Fab")
		)
		(fp_line
			(start 0.12065 -0.2794)
			(end -0.12065 -0.2794)
			(stroke
				(width 0.1)
				(type default)
			)
			(layer "B.Fab")
		)
		(fp_line
			(start 0.12065 0.2794)
			(end 0.12065 0.3048)
			(stroke
				(width 0.1)
				(type default)
			)
			(layer "B.Fab")
		)
		(fp_line
			(start 0.12065 0.3048)
			(end 0.67945 0.3048)
			(stroke
				(width 0.1)
				(type default)
			)
			(layer "B.Fab")
		)
		(fp_line
			(start 0.67945 -0.305054)
			(end 0.12065 -0.305054)
			(stroke
				(width 0.1)
				(type default)
			)
			(layer "B.Fab")
		)
		(fp_line
			(start 0.67945 0.3048)
			(end 0.67945 -0.305054)
			(stroke
				(width 0.1)
				(type default)
			)
			(layer "B.Fab")
		)
		(pad "1" smd circle
			(at 0.40005 0 180)
			(size 0 0)
			(layers "B.Cu" "B.Mask" "B.Paste")
			(net "P1V05_PCH_AUX")
		)
		(pad "2" smd circle
			(at -0.40005 0 180)
			(size 0 0)
			(layers "B.Cu" "B.Mask" "B.Paste")
			(net "FM_MFG_MODE")
		)
	)
	(footprint ""
		(layer "B.Cu")
		(at 175.355758 -111.375444 180)
		(property "Reference" "C1905"
			(at 0 0 0)
			(layer "B.SilkS")
			(hide yes)
			(effects
				(font
					(size 1.27 1.27)
				)
				(justify mirror)
			)
		)
		(property "Value" ""
			(at 0 0 0)
			(layer "B.Fab")
			(effects
				(font
					(size 1.27 1.27)
				)
				(justify mirror)
			)
		)
		(duplicate_pad_numbers_are_jumpers no)
		(fp_line
			(start 0.69215 0.2921)
			(end 0.69215 -0.2921)
			(stroke
				(width 0.1524)
				(type default)
			)
			(layer "B.SilkS")
		)
		(fp_line
			(start 0.69215 -0.2921)
			(end -0.69215 -0.2921)
			(stroke
				(width 0.1524)
				(type default)
			)
			(layer "B.SilkS")
		)
		(fp_line
			(start -0.69215 0.2921)
			(end 0.69215 0.2921)
			(stroke
				(width 0.1524)
				(type default)
			)
			(layer "B.SilkS")
		)
		(fp_line
			(start -0.69215 -0.2921)
			(end -0.69215 0.2921)
			(stroke
				(width 0.1524)
				(type default)
			)
			(layer "B.SilkS")
		)
		(fp_line
			(start 0.51435 0.2794)
			(end 0.51435 -0.2794)
			(stroke
				(width 0.1)
				(type default)
			)
			(layer "B.Fab")
		)
		(fp_line
			(start 0.51435 -0.2794)
			(end -0.51435 -0.2794)
			(stroke
				(width 0.1)
				(type default)
			)
			(layer "B.Fab")
		)
		(fp_line
			(start -0.51435 0.2794)
			(end 0.51435 0.2794)
			(stroke
				(width 0.1)
				(type default)
			)
			(layer "B.Fab")
		)
		(fp_line
			(start -0.51435 -0.2794)
			(end -0.51435 0.2794)
			(stroke
				(width 0.1)
				(type default)
			)
			(layer "B.Fab")
		)
		(pad "1" smd circle
			(at 0.40005 0)
			(size 0 0)
			(layers "B.Cu" "B.Mask" "B.Paste")
			(net "P3V3_AUX_FPGA_VCCIO0")
		)
		(pad "2" smd circle
			(at -0.40005 0)
			(size 0 0)
			(layers "B.Cu" "B.Mask" "B.Paste")
			(net "GND")
		)
		(zone
			(layer "B.Cu")
			(hatch none 0.5)
			(connect_pads
				(clearance 0)
			)
			(min_thickness 0.25)
			(keepout
				(tracks not_allowed)
				(vias allowed)
				(pads allowed)
				(copperpour not_allowed)
				(footprints allowed)
			)
			(placement
				(enabled no)
				(sheetname "")
			)
			(fill
				(thermal_gap 0.5)
				(thermal_bridge_width 0.5)
				(island_removal_mode 0)
			)
			(polygon
				(pts
					(xy 175.165258 -111.463074) (xy 175.256698 -111.52124) (xy 175.456088 -111.52124) (xy 175.546258 -111.463074)
					(xy 175.546258 -111.287814) (xy 175.456088 -111.229394) (xy 175.256698 -111.229394) (xy 175.165258 -111.28756)
				)
			)
		)
	)
	(footprint ""
		(layer "B.Cu")
		(at 459.982316 -318.608456 90)
		(property "Reference" "R2734"
			(at 0 0 90)
			(layer "B.SilkS")
			(hide yes)
			(effects
				(font
					(size 1.27 1.27)
				)
				(justify mirror)
			)
		)
		(property "Value" ""
			(at 0 0 90)
			(layer "B.Fab")
			(effects
				(font
					(size 1.27 1.27)
				)
				(justify mirror)
			)
		)
		(duplicate_pad_numbers_are_jumpers no)
		(fp_line
			(start 0.7874 -0.4064)
			(end -0.7874 -0.4064)
			(stroke
				(width 0.1524)
				(type default)
			)
			(layer "B.SilkS")
		)
		(fp_line
			(start -0.7874 -0.4064)
			(end -0.7874 0.4064)
			(stroke
				(width 0.1524)
				(type default)
			)
			(layer "B.SilkS")
		)
		(fp_line
			(start 0.7874 0.4064)
			(end 0.7874 -0.4064)
			(stroke
				(width 0.1524)
				(type default)
			)
			(layer "B.SilkS")
		)
		(fp_line
			(start -0.7874 0.4064)
			(end 0.7874 0.4064)
			(stroke
				(width 0.1524)
				(type default)
			)
			(layer "B.SilkS")
		)
		(fp_line
			(start 0.67945 -0.305054)
			(end 0.12065 -0.305054)
			(stroke
				(width 0.1)
				(type default)
			)
			(layer "B.Fab")
		)
		(fp_line
			(start 0.12065 -0.305054)
			(end 0.12065 -0.2794)
			(stroke
				(width 0.1)
				(type default)
			)
			(layer "B.Fab")
		)
		(fp_line
			(start -0.12065 -0.3048)
			(end -0.67945 -0.3048)
			(stroke
				(width 0.1)
				(type default)
			)
			(layer "B.Fab")
		)
		(fp_line
			(start -0.67945 -0.3048)
			(end -0.67945 0.3048)
			(stroke
				(width 0.1)
				(type default)
			)
			(layer "B.Fab")
		)
		(fp_line
			(start 0.12065 -0.2794)
			(end -0.12065 -0.2794)
			(stroke
				(width 0.1)
				(type default)
			)
			(layer "B.Fab")
		)
		(fp_line
			(start -0.12065 -0.2794)
			(end -0.12065 -0.3048)
			(stroke
				(width 0.1)
				(type default)
			)
			(layer "B.Fab")
		)
		(fp_line
			(start 0.12065 0.2794)
			(end 0.12065 0.3048)
			(stroke
				(width 0.1)
				(type default)
			)
			(layer "B.Fab")
		)
		(fp_line
			(start -0.120396 0.2794)
			(end 0.12065 0.2794)
			(stroke
				(width 0.1)
				(type default)
			)
			(layer "B.Fab")
		)
		(fp_line
			(start 0.67945 0.3048)
			(end 0.67945 -0.305054)
			(stroke
				(width 0.1)
				(type default)
			)
			(layer "B.Fab")
		)
		(fp_line
			(start 0.12065 0.3048)
			(end 0.67945 0.3048)
			(stroke
				(width 0.1)
				(type default)
			)
			(layer "B.Fab")
		)
		(fp_line
			(start -0.120396 0.3048)
			(end -0.120396 0.2794)
			(stroke
				(width 0.1)
				(type default)
			)
			(layer "B.Fab")
		)
		(fp_line
			(start -0.67945 0.3048)
			(end -0.120396 0.3048)
			(stroke
				(width 0.1)
				(type default)
			)
			(layer "B.Fab")
		)
		(pad "1" smd circle
			(at 0.40005 0 270)
			(size 0 0)
			(layers "B.Cu" "B.Mask" "B.Paste")
			(net "PWRGD_CHH_CPU0_DIMM1")
		)
		(pad "2" smd circle
			(at -0.40005 0 270)
			(size 0 0)
			(layers "B.Cu" "B.Mask" "B.Paste")
			(net "PWRGD_FAIL_CPU0_GH")
		)
	)
)
